(kicad_pcb
	(version 20260206)
	(generator "pcbnew")
	(generator_version "10.0")
	(general
		(thickness 1.6)
		(legacy_teardrops no)
	)
	(paper "A4")
	(title_block
		(title "baseboard — 13948-1b.1110WZS1818.brd")
		(comment 1 "Honey Badger (Wiwynn) / footprints 241-248 of 2523")
	)
	(layers
		(0 "F.Cu" signal "TOP")
		(4 "In1.Cu" signal "L2GND")
		(6 "In2.Cu" signal "L3")
		(8 "In3.Cu" signal "L4VCC")
		(10 "In4.Cu" signal "L5VCC")
		(12 "In5.Cu" signal "L6")
		(14 "In6.Cu" signal "L7GND")
		(2 "B.Cu" signal "BOTTOM")
		(9 "F.Adhes" user "F.Adhesive")
		(11 "B.Adhes" user "B.Adhesive")
		(13 "F.Paste" user "Package Geometry/Pastemask Top")
		(15 "B.Paste" user "Package Geometry/Pastemask Bottom")
		(5 "F.SilkS" user "Ref Des/Silkscreen Top")
		(7 "B.SilkS" user "Ref Des/Silkscreen Bottom")
		(1 "F.Mask" user "Board Geometry/Soldermask Top")
		(3 "B.Mask" user "Board Geometry/Soldermask Bottom")
		(17 "Dwgs.User" user "User.Drawings")
		(19 "Cmts.User" user "User.Comments")
		(21 "Eco1.User" user "User.Eco1")
		(23 "Eco2.User" user "User.Eco2")
		(25 "Edge.Cuts" user "Board Geometry/Outline")
		(27 "Margin" user)
		(31 "F.CrtYd" user "Package Geometry/Place Bound Top")
		(29 "B.CrtYd" user "Package Geometry/Place Bound Bottom")
		(35 "F.Fab" user "Ref Des/Assembly Top")
		(33 "B.Fab" user "Ref Des/Assembly Bottom")
	)
	(footprint ""
		(layer "F.Cu")
		(at 219.075 -162.433 90)
		(property "Reference" "U182"
			(at 0 0 90)
			(layer "F.SilkS")
			(hide yes)
			(effects
				(font
					(size 1.27 1.27)
				)
			)
		)
		(property "Value" "74AVC1T45DCKR-GP"
			(at -2.3622 -8.2042 90)
			(unlocked yes)
			(layer "F.Fab")
			(hide yes)
			(effects
				(font
					(size 1.016 1.016)
					(thickness 0.1524)
				)
			)
		)
		(property "Device Type" "SC70-6H44"
			(at -2.3622 -10.1092 90)
			(unlocked yes)
			(layer "F.Fab")
			(hide yes)
			(effects
				(font
					(size 1.016 1.016)
					(thickness 0.1524)
				)
			)
		)
		(duplicate_pad_numbers_are_jumpers no)
		(fp_line
			(start 1.4478 -1.7018)
			(end -1.4478 -1.7018)
			(stroke
				(width 0.1524)
				(type default)
			)
			(layer "F.SilkS")
		)
		(fp_line
			(start -1.4478 -1.7018)
			(end -1.4478 1.7018)
			(stroke
				(width 0.1524)
				(type default)
			)
			(layer "F.SilkS")
		)
		(fp_line
			(start 1.4478 1.7018)
			(end 1.4478 -1.7018)
			(stroke
				(width 0.1524)
				(type default)
			)
			(layer "F.SilkS")
		)
		(fp_line
			(start -1.4478 1.7018)
			(end 1.4478 1.7018)
			(stroke
				(width 0.1524)
				(type default)
			)
			(layer "F.SilkS")
		)
		(fp_line
			(start -0.5715 1.7907)
			(end -1.5494 1.7907)
			(stroke
				(width 0.3302)
				(type default)
			)
			(layer "F.SilkS")
		)
		(fp_line
			(start -1.5494 1.7907)
			(end -1.5494 0.8255)
			(stroke
				(width 0.3302)
				(type default)
			)
			(layer "F.SilkS")
		)
		(fp_poly
			(pts
				(xy -0.6604 1.7272) (xy -1.016 2.0828) (xy -0.3048 2.0828)
			)
			(stroke
				(width 0)
				(type default)
			)
			(fill yes)
			(layer "F.SilkS")
		)
		(fp_poly
			(pts
				(xy -1.524 -1.778) (xy 1.524 -1.778) (xy 1.524 1.778) (xy -1.524 1.778)
			)
			(stroke
				(width 0)
				(type default)
			)
			(fill no)
			(layer "F.CrtYd")
		)
		(fp_poly
			(pts
				(xy -1.524 -1.778) (xy 1.524 -1.778) (xy 1.524 1.778) (xy -1.524 1.778)
			)
			(stroke
				(width 0)
				(type default)
			)
			(fill no)
			(layer "F.Fab")
		)
		(pad "1" smd rect
			(at -0.65024 0.9398 90)
			(size 0.4064 1.016)
			(layers "F.Cu" "F.Mask" "F.Paste")
			(net "P3V3_STBY")
		)
		(pad "2" smd rect
			(at 0 0.9398 90)
			(size 0.4064 1.016)
			(layers "F.Cu" "F.Mask" "F.Paste")
			(net "GND")
		)
		(pad "3" smd rect
			(at 0.65024 0.9398 90)
			(size 0.4064 1.016)
			(layers "F.Cu" "F.Mask" "F.Paste")
			(net "JTAG_IOC_TDO_L")
		)
		(pad "4" smd rect
			(at 0.65024 -0.9398 90)
			(size 0.4064 1.016)
			(layers "F.Cu" "F.Mask" "F.Paste")
			(net "JTAG_IOC_TDO")
		)
		(pad "5" smd rect
			(at 0 -0.9398 90)
			(size 0.4064 1.016)
			(layers "F.Cu" "F.Mask" "F.Paste")
			(net "GND")
		)
		(pad "6" smd rect
			(at -0.65024 -0.9398 90)
			(size 0.4064 1.016)
			(layers "F.Cu" "F.Mask" "F.Paste")
			(net "P1V8_STBY")
		)
	)
	(footprint ""
		(layer "F.Cu")
		(at 208.407 -101.092 -90)
		(property "Reference" "PC142"
			(at 0 0 270)
			(layer "F.SilkS")
			(hide yes)
			(effects
				(font
					(size 1.27 1.27)
				)
			)
		)
		(property "Value" "SC10U6D3V5KX-1GP"
			(at -0.0762 -6.1214 270)
			(unlocked yes)
			(layer "F.Fab")
			(hide yes)
			(effects
				(font
					(size 1.016 1.016)
					(thickness 0.1524)
				)
			)
		)
		(property "Device Type" "C805H54"
			(at -0.0762 -8.1534 270)
			(unlocked yes)
			(layer "F.Fab")
			(hide yes)
			(effects
				(font
					(size 1.016 1.016)
					(thickness 0.1524)
				)
			)
		)
		(duplicate_pad_numbers_are_jumpers no)
		(fp_line
			(start 0.635 0)
			(end -0.635 0)
			(stroke
				(width 0.508)
				(type default)
			)
			(layer "F.SilkS")
		)
		(fp_rect
			(start -0.9652 1.778)
			(end 0.9652 -1.778)
			(stroke
				(width 0)
				(type default)
			)
			(fill no)
			(layer "F.CrtYd")
		)
		(fp_poly
			(pts
				(xy -0.9652 -1.778) (xy 0.9652 -1.778) (xy 0.9652 1.778) (xy -0.9652 1.778)
			)
			(stroke
				(width 0)
				(type default)
			)
			(fill no)
			(layer "F.Fab")
		)
		(pad "1" smd rect
			(at 0 -0.9652 270)
			(size 1.397 1.143)
			(layers "F.Cu" "F.Mask" "F.Paste")
			(net "P1V5_C")
		)
		(pad "2" smd rect
			(at 0 0.9652 270)
			(size 1.397 1.143)
			(layers "F.Cu" "F.Mask" "F.Paste")
			(net "GND")
		)
	)
	(footprint ""
		(layer "F.Cu")
		(at 318.008 -174.752 -90)
		(property "Reference" "R582"
			(at 0 0 270)
			(layer "F.SilkS")
			(hide yes)
			(effects
				(font
					(size 1.27 1.27)
				)
			)
		)
		(property "Value" "0R2J-2-GP"
			(at 0.064008 -3.993896 270)
			(unlocked yes)
			(layer "F.Fab")
			(hide yes)
			(effects
				(font
					(size 1.016 1.016)
					(thickness 0.1524)
				)
			)
		)
		(property "Device Type" "R402H16"
			(at 0.064008 -5.517896 270)
			(unlocked yes)
			(layer "F.Fab")
			(hide yes)
			(effects
				(font
					(size 1.016 1.016)
					(thickness 0.1524)
				)
			)
		)
		(duplicate_pad_numbers_are_jumpers no)
		(fp_line
			(start -0.508 -0.9398)
			(end -0.508 0.9398)
			(stroke
				(width 0.1524)
				(type default)
			)
			(layer "F.SilkS")
		)
		(fp_line
			(start 0.508 -0.9398)
			(end -0.508 -0.9398)
			(stroke
				(width 0.1524)
				(type default)
			)
			(layer "F.SilkS")
		)
		(fp_rect
			(start -0.508 0.9398)
			(end 0.508 -0.9398)
			(stroke
				(width 0)
				(type default)
			)
			(fill no)
			(layer "F.CrtYd")
		)
		(fp_rect
			(start -0.508 0.9398)
			(end 0.508 -0.9398)
			(stroke
				(width 0)
				(type default)
			)
			(fill no)
			(layer "F.Fab")
		)
		(pad "1" smd custom
			(at 0 -0.4445 270)
			(size 0.1397 0.1397)
			(layers "F.Cu" "F.Mask" "F.Paste")
			(net "BMC_JTAG_L")
			(options
				(clearance outline)
				(anchor circle)
			)
			(primitives
				(gr_poly
					(pts
						(arc
							(start -0.1778 -0.2794)
							(mid -0.249642 -0.249642)
							(end -0.2794 -0.1778)
						)
						(arc
							(start -0.2794 0.1778)
							(mid -0.249642 0.249642)
							(end -0.1778 0.2794)
						)
						(arc
							(start 0.1778 0.2794)
							(mid 0.249642 0.249642)
							(end 0.2794 0.1778)
						)
						(arc
							(start 0.2794 -0.1778)
							(mid 0.249642 -0.249642)
							(end 0.1778 -0.2794)
						)
					)
					(width 0)
					(fill yes)
				)
			)
		)
		(pad "2" smd custom
			(at 0 0.4445 270)
			(size 0.1397 0.1397)
			(layers "F.Cu" "F.Mask" "F.Paste")
			(net "BMC_JTAG_L_R")
			(options
				(clearance outline)
				(anchor circle)
			)
			(primitives
				(gr_poly
					(pts
						(arc
							(start -0.1778 -0.2794)
							(mid -0.249642 -0.249642)
							(end -0.2794 -0.1778)
						)
						(arc
							(start -0.2794 0.1778)
							(mid -0.249642 0.249642)
							(end -0.1778 0.2794)
						)
						(arc
							(start 0.1778 0.2794)
							(mid 0.249642 0.249642)
							(end 0.2794 0.1778)
						)
						(arc
							(start 0.2794 -0.1778)
							(mid 0.249642 -0.249642)
							(end 0.1778 -0.2794)
						)
					)
					(width 0)
					(fill yes)
				)
			)
		)
	)
	(footprint ""
		(layer "F.Cu")
		(at 233.426 -17.907 -90)
		(property "Reference" "R532"
			(at 0 0 270)
			(layer "F.SilkS")
			(hide yes)
			(effects
				(font
					(size 1.27 1.27)
				)
			)
		)
		(property "Value" "1KR2F-3-GP"
			(at 0.064008 -3.993896 270)
			(unlocked yes)
			(layer "F.Fab")
			(hide yes)
			(effects
				(font
					(size 1.016 1.016)
					(thickness 0.1524)
				)
			)
		)
		(property "Device Type" "R402H16"
			(at 0.064008 -5.517896 270)
			(unlocked yes)
			(layer "F.Fab")
			(hide yes)
			(effects
				(font
					(size 1.016 1.016)
					(thickness 0.1524)
				)
			)
		)
		(duplicate_pad_numbers_are_jumpers no)
		(fp_line
			(start -0.508 -0.9398)
			(end -0.508 0.9398)
			(stroke
				(width 0.1524)
				(type default)
			)
			(layer "F.SilkS")
		)
		(fp_line
			(start 0.508 -0.9398)
			(end -0.508 -0.9398)
			(stroke
				(width 0.1524)
				(type default)
			)
			(layer "F.SilkS")
		)
		(fp_rect
			(start -0.508 0.9398)
			(end 0.508 -0.9398)
			(stroke
				(width 0)
				(type default)
			)
			(fill no)
			(layer "F.CrtYd")
		)
		(fp_rect
			(start -0.508 0.9398)
			(end 0.508 -0.9398)
			(stroke
				(width 0)
				(type default)
			)
			(fill no)
			(layer "F.Fab")
		)
		(pad "1" smd custom
			(at 0 -0.4445 270)
			(size 0.1397 0.1397)
			(layers "F.Cu" "F.Mask" "F.Paste")
			(net "ENCLO_LED_BLUE_OUT")
			(options
				(clearance outline)
				(anchor circle)
			)
			(primitives
				(gr_poly
					(pts
						(arc
							(start -0.1778 -0.2794)
							(mid -0.249642 -0.249642)
							(end -0.2794 -0.1778)
						)
						(arc
							(start -0.2794 0.1778)
							(mid -0.249642 0.249642)
							(end -0.1778 0.2794)
						)
						(arc
							(start 0.1778 0.2794)
							(mid 0.249642 0.249642)
							(end 0.2794 0.1778)
						)
						(arc
							(start 0.2794 -0.1778)
							(mid 0.249642 -0.249642)
							(end 0.1778 -0.2794)
						)
					)
					(width 0)
					(fill yes)
				)
			)
		)
		(pad "2" smd custom
			(at 0 0.4445 270)
			(size 0.1397 0.1397)
			(layers "F.Cu" "F.Mask" "F.Paste")
			(net "ENCLO_LED_RED_G")
			(options
				(clearance outline)
				(anchor circle)
			)
			(primitives
				(gr_poly
					(pts
						(arc
							(start -0.1778 -0.2794)
							(mid -0.249642 -0.249642)
							(end -0.2794 -0.1778)
						)
						(arc
							(start -0.2794 0.1778)
							(mid -0.249642 0.249642)
							(end -0.1778 0.2794)
						)
						(arc
							(start 0.1778 0.2794)
							(mid 0.249642 0.249642)
							(end 0.2794 0.1778)
						)
						(arc
							(start 0.2794 -0.1778)
							(mid 0.249642 -0.249642)
							(end 0.1778 -0.2794)
						)
					)
					(width 0)
					(fill yes)
				)
			)
		)
	)
	(footprint ""
		(layer "F.Cu")
		(at 303.911 -192.913 180)
		(property "Reference" "C85"
			(at 0 0 180)
			(layer "F.SilkS")
			(hide yes)
			(effects
				(font
					(size 1.27 1.27)
				)
			)
		)
		(property "Value" "SCD1U16V2KX-3GP"
			(at 1.1811 -2.7051 180)
			(unlocked yes)
			(layer "F.Fab")
			(hide yes)
			(effects
				(font
					(size 1.016 1.016)
					(thickness 0.1524)
				)
			)
		)
		(property "Device Type" "C402H22"
			(at 1.1811 -4.2291 180)
			(unlocked yes)
			(layer "F.Fab")
			(hide yes)
			(effects
				(font
					(size 1.016 1.016)
					(thickness 0.1524)
				)
			)
		)
		(duplicate_pad_numbers_are_jumpers no)
		(fp_rect
			(start -0.4318 0.9525)
			(end 0.4318 -0.9525)
			(stroke
				(width 0)
				(type default)
			)
			(fill no)
			(layer "F.CrtYd")
		)
		(fp_rect
			(start -0.4318 0.9525)
			(end 0.4318 -0.9525)
			(stroke
				(width 0)
				(type default)
			)
			(fill no)
			(layer "F.Fab")
		)
		(pad "1" smd custom
			(at 0 -0.4445 180)
			(size 0.1524 0.1524)
			(layers "F.Cu" "F.Mask" "F.Paste")
			(net "P3V3_STBY")
			(options
				(clearance outline)
				(anchor circle)
			)
			(primitives
				(gr_poly
					(pts
						(arc
							(start 0.3048 -0.2032)
							(mid 0.275042 -0.275042)
							(end 0.2032 -0.3048)
						)
						(arc
							(start -0.2032 -0.3048)
							(mid -0.275042 -0.275042)
							(end -0.3048 -0.2032)
						)
						(arc
							(start -0.3048 0.2032)
							(mid -0.275042 0.275042)
							(end -0.2032 0.3048)
						)
						(arc
							(start 0.2032 0.3048)
							(mid 0.275042 0.275042)
							(end 0.3048 0.2032)
						)
					)
					(width 0)
					(fill yes)
				)
			)
		)
		(pad "2" smd custom
			(at 0 0.4445 180)
			(size 0.1524 0.1524)
			(layers "F.Cu" "F.Mask" "F.Paste")
			(net "GND")
			(options
				(clearance outline)
				(anchor circle)
			)
			(primitives
				(gr_poly
					(pts
						(arc
							(start 0.3048 -0.2032)
							(mid 0.275042 -0.275042)
							(end 0.2032 -0.3048)
						)
						(arc
							(start -0.2032 -0.3048)
							(mid -0.275042 -0.275042)
							(end -0.3048 -0.2032)
						)
						(arc
							(start -0.3048 0.2032)
							(mid -0.275042 0.275042)
							(end -0.2032 0.3048)
						)
						(arc
							(start 0.2032 0.3048)
							(mid 0.275042 0.275042)
							(end 0.3048 0.2032)
						)
					)
					(width 0)
					(fill yes)
				)
			)
		)
	)
	(footprint ""
		(layer "F.Cu")
		(at 300.482 -61.976 -90)
		(property "Reference" "R207"
			(at 0 0 270)
			(layer "F.SilkS")
			(hide yes)
			(effects
				(font
					(size 1.27 1.27)
				)
			)
		)
		(property "Value" "0R2J-2-GP"
			(at 0.064008 -3.993896 270)
			(unlocked yes)
			(layer "F.Fab")
			(hide yes)
			(effects
				(font
					(size 1.016 1.016)
					(thickness 0.1524)
				)
			)
		)
		(property "Device Type" "R402H16"
			(at 0.064008 -5.517896 270)
			(unlocked yes)
			(layer "F.Fab")
			(hide yes)
			(effects
				(font
					(size 1.016 1.016)
					(thickness 0.1524)
				)
			)
		)
		(duplicate_pad_numbers_are_jumpers no)
		(fp_line
			(start -0.508 -0.9398)
			(end -0.508 0.9398)
			(stroke
				(width 0.1524)
				(type default)
			)
			(layer "F.SilkS")
		)
		(fp_line
			(start 0.508 -0.9398)
			(end -0.508 -0.9398)
			(stroke
				(width 0.1524)
				(type default)
			)
			(layer "F.SilkS")
		)
		(fp_rect
			(start -0.508 0.9398)
			(end 0.508 -0.9398)
			(stroke
				(width 0)
				(type default)
			)
			(fill no)
			(layer "F.CrtYd")
		)
		(fp_rect
			(start -0.508 0.9398)
			(end 0.508 -0.9398)
			(stroke
				(width 0)
				(type default)
			)
			(fill no)
			(layer "F.Fab")
		)
		(pad "1" smd custom
			(at 0 -0.4445 270)
			(size 0.1397 0.1397)
			(layers "F.Cu" "F.Mask" "F.Paste")
			(net "PMU_WAKE_N_R")
			(options
				(clearance outline)
				(anchor circle)
			)
			(primitives
				(gr_poly
					(pts
						(arc
							(start -0.1778 -0.2794)
							(mid -0.249642 -0.249642)
							(end -0.2794 -0.1778)
						)
						(arc
							(start -0.2794 0.1778)
							(mid -0.249642 0.249642)
							(end -0.1778 0.2794)
						)
						(arc
							(start 0.1778 0.2794)
							(mid 0.249642 0.249642)
							(end 0.2794 0.1778)
						)
						(arc
							(start 0.2794 -0.1778)
							(mid 0.249642 -0.249642)
							(end 0.1778 -0.2794)
						)
					)
					(width 0)
					(fill yes)
				)
			)
		)
		(pad "2" smd custom
			(at 0 0.4445 270)
			(size 0.1397 0.1397)
			(layers "F.Cu" "F.Mask" "F.Paste")
			(net "PMU_WAKE_N")
			(options
				(clearance outline)
				(anchor circle)
			)
			(primitives
				(gr_poly
					(pts
						(arc
							(start -0.1778 -0.2794)
							(mid -0.249642 -0.249642)
							(end -0.2794 -0.1778)
						)
						(arc
							(start -0.2794 0.1778)
							(mid -0.249642 0.249642)
							(end -0.1778 0.2794)
						)
						(arc
							(start 0.1778 0.2794)
							(mid 0.249642 0.249642)
							(end 0.2794 0.1778)
						)
						(arc
							(start 0.2794 -0.1778)
							(mid 0.249642 -0.249642)
							(end 0.1778 -0.2794)
						)
					)
					(width 0)
					(fill yes)
				)
			)
		)
	)
	(footprint ""
		(layer "F.Cu")
		(at 166.878 -101.473 180)
		(property "Reference" "PC183"
			(at 0 0 180)
			(layer "F.SilkS")
			(hide yes)
			(effects
				(font
					(size 1.27 1.27)
				)
			)
		)
		(property "Value" "SC47U6D3V5MX-1-GP"
			(at -0.0762 -6.1214 180)
			(unlocked yes)
			(layer "F.Fab")
			(hide yes)
			(effects
				(font
					(size 1.016 1.016)
					(thickness 0.1524)
				)
			)
		)
		(property "Device Type" "C805H54"
			(at -0.0762 -8.1534 180)
			(unlocked yes)
			(layer "F.Fab")
			(hide yes)
			(effects
				(font
					(size 1.016 1.016)
					(thickness 0.1524)
				)
			)
		)
		(duplicate_pad_numbers_are_jumpers no)
		(fp_line
			(start 0.635 0)
			(end -0.635 0)
			(stroke
				(width 0.508)
				(type default)
			)
			(layer "F.SilkS")
		)
		(fp_rect
			(start -0.9652 1.778)
			(end 0.9652 -1.778)
			(stroke
				(width 0)
				(type default)
			)
			(fill no)
			(layer "F.CrtYd")
		)
		(fp_poly
			(pts
				(xy -0.9652 -1.778) (xy 0.9652 -1.778) (xy 0.9652 1.778) (xy -0.9652 1.778)
			)
			(stroke
				(width 0)
				(type default)
			)
			(fill no)
			(layer "F.Fab")
		)
		(pad "1" smd rect
			(at 0 -0.9652 180)
			(size 1.397 1.143)
			(layers "F.Cu" "F.Mask" "F.Paste")
			(net "P0V9_E")
		)
		(pad "2" smd rect
			(at 0 0.9652 180)
			(size 1.397 1.143)
			(layers "F.Cu" "F.Mask" "F.Paste")
			(net "GND")
		)
	)
	(footprint ""
		(layer "F.Cu")
		(at 26.366216 -193.34988)
		(property "Reference" "R651"
			(at 0 0 0)
			(layer "F.SilkS")
			(hide yes)
			(effects
				(font
					(size 1.27 1.27)
				)
			)
		)
		(property "Value" "4K7R2F-GP"
			(at 0.064008 -3.993896 0)
			(unlocked yes)
			(layer "F.Fab")
			(hide yes)
			(effects
				(font
					(size 1.016 1.016)
					(thickness 0.1524)
				)
			)
		)
		(property "Device Type" "R402H16"
			(at 0.064008 -5.517896 0)
			(unlocked yes)
			(layer "F.Fab")
			(hide yes)
			(effects
				(font
					(size 1.016 1.016)
					(thickness 0.1524)
				)
			)
		)
		(duplicate_pad_numbers_are_jumpers no)
		(fp_line
			(start -0.508 -0.9398)
			(end -0.508 0.9398)
			(stroke
				(width 0.1524)
				(type default)
			)
			(layer "F.SilkS")
		)
		(fp_line
			(start 0.508 -0.9398)
			(end -0.508 -0.9398)
			(stroke
				(width 0.1524)
				(type default)
			)
			(layer "F.SilkS")
		)
		(fp_rect
			(start -0.508 0.9398)
			(end 0.508 -0.9398)
			(stroke
				(width 0)
				(type default)
			)
			(fill no)
			(layer "F.CrtYd")
		)
		(fp_rect
			(start -0.508 0.9398)
			(end 0.508 -0.9398)
			(stroke
				(width 0)
				(type default)
			)
			(fill no)
			(layer "F.Fab")
		)
		(pad "1" smd custom
			(at 0 -0.4445)
			(size 0.1397 0.1397)
			(layers "F.Cu" "F.Mask" "F.Paste")
			(net "P3V3_STBY")
			(options
				(clearance outline)
				(anchor circle)
			)
			(primitives
				(gr_poly
					(pts
						(arc
							(start -0.1778 -0.2794)
							(mid -0.249642 -0.249642)
							(end -0.2794 -0.1778)
						)
						(arc
							(start -0.2794 0.1778)
							(mid -0.249642 0.249642)
							(end -0.1778 0.2794)
						)
						(arc
							(start 0.1778 0.2794)
							(mid 0.249642 0.249642)
							(end 0.2794 0.1778)
						)
						(arc
							(start 0.2794 -0.1778)
							(mid 0.249642 -0.249642)
							(end 0.1778 -0.2794)
						)
					)
					(width 0)
					(fill yes)
				)
			)
		)
		(pad "2" smd custom
			(at 0 0.4445)
			(size 0.1397 0.1397)
			(layers "F.Cu" "F.Mask" "F.Paste")
			(net "IO_EXP_HDD_PRE_A0")
			(options
				(clearance outline)
				(anchor circle)
			)
			(primitives
				(gr_poly
					(pts
						(arc
							(start -0.1778 -0.2794)
							(mid -0.249642 -0.249642)
							(end -0.2794 -0.1778)
						)
						(arc
							(start -0.2794 0.1778)
							(mid -0.249642 0.249642)
							(end -0.1778 0.2794)
						)
						(arc
							(start 0.1778 0.2794)
							(mid 0.249642 0.249642)
							(end 0.2794 0.1778)
						)
						(arc
							(start 0.2794 -0.1778)
							(mid 0.249642 -0.249642)
							(end 0.1778 -0.2794)
						)
					)
					(width 0)
					(fill yes)
				)
			)
		)
	)
)
